# BASEBOARD_FAB2 (Tioga Pass) — schematic netlist excerpt (pin names and nets, part order shuffled) for the footprints in the layout excerpt that follows; sources: Cadence DE-HDL packaged netlist, KiCad conversion of Wiwynn_Tioga_Pass_MB.brd

C6L4  CAP  10UF 4V 20% X6S  pkg 0603LF  page 222 : A = PVDDQ_DEF ; B = GND

U4R1  74CBTLV1G125  IC  pkg SMLF  page 113
  OE_N  = FM_CPU0_PKGID1
  A  = P1V8_MCP_CPU0
  B  = JTAG_MCP_CPU0_TDI_R

C5T2  CAP_A  47UF 4V 20% X5R  pkg 0603V  page 217 : A = PVDDQ_ABC ; B = GND

(kicad_pcb
	(version 20260206)
	(generator "pcbnew")
	(generator_version "10.0")
	(general
		(thickness 1.6)
		(legacy_teardrops no)
	)
	(paper "A4")
	(title_block
		(title "Wiwynn_Tioga_Pass_MB.brd")
		(comment 1 "Tioga Pass / footprints 4306-4308 of 4770")
	)
	(layers
		(0 "F.Cu" signal "TOP")
		(4 "In1.Cu" signal "L2GND")
		(6 "In2.Cu" signal "L3")
		(8 "In3.Cu" signal "L4GND")
		(10 "In4.Cu" signal "L5")
		(12 "In5.Cu" signal "L6GND")
		(14 "In6.Cu" signal "L7VCC")
		(16 "In7.Cu" signal "L8VCC")
		(18 "In8.Cu" signal "L9GND")
		(20 "In9.Cu" signal "L10")
		(22 "In10.Cu" signal "L11GND")
		(24 "In11.Cu" signal "L12")
		(26 "In12.Cu" signal "L13GND")
		(2 "B.Cu" signal "BOTTOM")
		(9 "F.Adhes" user "F.Adhesive")
		(11 "B.Adhes" user "B.Adhesive")
		(13 "F.Paste" user "Package Geometry/Pastemask Top")
		(15 "B.Paste" user "Package Geometry/Pastemask Bottom")
		(5 "F.SilkS" user "Ref Des/Silkscreen Top")
		(7 "B.SilkS" user "Ref Des/Silkscreen Bottom")
		(1 "F.Mask" user "Board Geometry/Soldermask Top")
		(3 "B.Mask" user "Board Geometry/Soldermask Bottom")
		(17 "Dwgs.User" user "User.Drawings")
		(19 "Cmts.User" user "User.Comments")
		(21 "Eco1.User" user "User.Eco1")
		(23 "Eco2.User" user "User.Eco2")
		(25 "Edge.Cuts" user "Board Geometry/Outline")
		(27 "Margin" user)
		(31 "F.CrtYd" user "Package Geometry/Place Bound Top")
		(29 "B.CrtYd" user "Package Geometry/Place Bound Bottom")
		(35 "F.Fab" user "Ref Des/Assembly Top")
		(33 "B.Fab" user "Ref Des/Assembly Bottom")
	)
	(footprint ""
		(layer "B.Cu")
		(at 245.7196 -27.2034 90)
		(property "Reference" "C5T2"
			(at 0 0 90)
			(layer "B.SilkS")
			(hide yes)
			(effects
				(font
					(size 1.27 1.27)
				)
				(justify mirror)
			)
		)
		(property "Value" ""
			(at 0 0 90)
			(layer "B.Fab")
			(effects
				(font
					(size 1.27 1.27)
				)
				(justify mirror)
			)
		)
		(duplicate_pad_numbers_are_jumpers no)
		(fp_rect
			(start 0.500126 1.598422)
			(end -0.500126 -0.201422)
			(stroke
				(width 0)
				(type default)
			)
			(fill no)
			(layer "B.CrtYd")
		)
		(fp_line
			(start 0.500126 -0.201422)
			(end -0.500126 -0.201422)
			(stroke
				(width 0.1)
				(type default)
			)
			(layer "B.Fab")
		)
		(fp_line
			(start -0.500126 -0.201422)
			(end -0.500126 1.598422)
			(stroke
				(width 0.1)
				(type default)
			)
			(layer "B.Fab")
		)
		(fp_line
			(start 0.500126 1.598422)
			(end 0.500126 -0.201422)
			(stroke
				(width 0.1)
				(type default)
			)
			(layer "B.Fab")
		)
		(fp_line
			(start -0.500126 1.598422)
			(end 0.500126 1.598422)
			(stroke
				(width 0.1)
				(type default)
			)
			(layer "B.Fab")
		)
		(pad "1" smd rect
			(at 0 0)
			(size 0.889 0.9906)
			(layers "B.Cu" "B.Mask" "B.Paste")
			(net "PVDDQ_ABC")
		)
		(pad "2" smd rect
			(at 0 1.397)
			(size 0.889 0.9906)
			(layers "B.Cu" "B.Mask" "B.Paste")
			(net "GND")
		)
		(zone
			(layer "B.Cu")
			(hatch none 0.5)
			(connect_pads
				(clearance 0)
			)
			(min_thickness 0.25)
			(keepout
				(tracks not_allowed)
				(vias allowed)
				(pads allowed)
				(copperpour not_allowed)
				(footprints allowed)
			)
			(placement
				(enabled no)
				(sheetname "")
			)
			(fill
				(thermal_gap 0.5)
				(thermal_bridge_width 0.5)
				(island_removal_mode 0)
			)
			(polygon
				(pts
					(xy 246.6721 -27.6987) (xy 246.1641 -27.6987) (xy 246.1641 -26.7081) (xy 246.6721 -26.7081)
				)
			)
		)
		(zone
			(layer "B.Cu")
			(hatch none 0.5)
			(connect_pads
				(clearance 0)
			)
			(min_thickness 0.25)
			(keepout
				(tracks allowed)
				(vias not_allowed)
				(pads allowed)
				(copperpour not_allowed)
				(footprints allowed)
			)
			(placement
				(enabled no)
				(sheetname "")
			)
			(fill
				(thermal_gap 0.5)
				(thermal_bridge_width 0.5)
				(island_removal_mode 0)
			)
			(polygon
				(pts
					(xy 246.6721 -27.6987) (xy 246.1641 -27.6987) (xy 246.1641 -26.7081) (xy 246.6721 -26.7081)
				)
			)
		)
	)
	(footprint ""
		(layer "B.Cu")
		(at 329.356466 -57.916318)
		(property "Reference" "U4R1"
			(at -2.794 0.87503 0)
			(unlocked yes)
			(layer "B.SilkS")
			(effects
				(font
					(size 0.7874 0.5842)
					(thickness 0.1524)
				)
				(justify left mirror)
			)
		)
		(property "Value" ""
			(at 0 0 0)
			(layer "B.Fab")
			(effects
				(font
					(size 1.27 1.27)
				)
				(justify mirror)
			)
		)
		(duplicate_pad_numbers_are_jumpers no)
		(fp_circle
			(center 0.4699 -0.8382)
			(end 0.5969 -0.8382)
			(stroke
				(width 0.254)
				(type default)
			)
			(fill no)
			(layer "B.SilkS")
		)
		(fp_poly
			(pts
				(xy -0.21463 -0.450088) (xy -1.56337 -0.450088) (xy -1.56337 1.75006) (xy -0.21463 1.75006)
			)
			(stroke
				(width 0)
				(type default)
			)
			(fill no)
			(layer "B.CrtYd")
		)
		(fp_line
			(start -1.56337 -0.450088)
			(end -1.56337 1.75006)
			(stroke
				(width 0.1)
				(type default)
			)
			(layer "B.Fab")
		)
		(fp_line
			(start -1.56337 1.75006)
			(end -0.21463 1.75006)
			(stroke
				(width 0.1)
				(type default)
			)
			(layer "B.Fab")
		)
		(fp_line
			(start -0.21463 -0.450088)
			(end -1.56337 -0.450088)
			(stroke
				(width 0.1)
				(type default)
			)
			(layer "B.Fab")
		)
		(fp_line
			(start -0.21463 1.75006)
			(end -0.21463 -0.450088)
			(stroke
				(width 0.1)
				(type default)
			)
			(layer "B.Fab")
		)
		(fp_circle
			(center 0.4699 -0.8382)
			(end 0.5969 -0.8382)
			(stroke
				(width 0.254)
				(type default)
			)
			(fill no)
			(layer "B.Fab")
		)
		(pad "1" smd rect
			(at 0 0 180)
			(size 1.016 0.381)
			(layers "B.Cu" "B.Mask" "B.Paste")
			(net "FM_CPU0_PKGID1")
		)
		(pad "2" smd rect
			(at 0 0.649986 180)
			(size 1.016 0.381)
			(layers "B.Cu" "B.Mask" "B.Paste")
			(net "P1V8_MCP_CPU0")
		)
		(pad "3" smd rect
			(at 0 1.299972 180)
			(size 1.016 0.381)
			(layers "B.Cu" "B.Mask" "B.Paste")
			(net "GND")
		)
		(pad "4" smd rect
			(at -1.778 1.299972 180)
			(size 1.016 0.381)
			(layers "B.Cu" "B.Mask" "B.Paste")
			(net "JTAG_MCP_CPU0_TDI_R")
		)
		(pad "5" smd rect
			(at -1.778 0 180)
			(size 1.016 0.381)
			(layers "B.Cu" "B.Mask" "B.Paste")
			(net "P3V3_STBY")
		)
	)
	(footprint ""
		(layer "B.Cu")
		(at 180.873654 -150.815548)
		(property "Reference" "C6L4"
			(at 0 0 0)
			(layer "B.SilkS")
			(hide yes)
			(effects
				(font
					(size 1.27 1.27)
				)
				(justify mirror)
			)
		)
		(property "Value" ""
			(at 0 0 0)
			(layer "B.Fab")
			(effects
				(font
					(size 1.27 1.27)
				)
				(justify mirror)
			)
		)
		(duplicate_pad_numbers_are_jumpers no)
		(fp_rect
			(start 0.4953 -0.2032)
			(end -0.4953 1.6002)
			(stroke
				(width 0)
				(type default)
			)
			(fill no)
			(layer "B.CrtYd")
		)
		(fp_line
			(start -0.4953 -0.2032)
			(end -0.4953 1.6002)
			(stroke
				(width 0.1)
				(type default)
			)
			(layer "B.Fab")
		)
		(fp_line
			(start -0.4953 1.6002)
			(end 0.4953 1.6002)
			(stroke
				(width 0.1)
				(type default)
			)
			(layer "B.Fab")
		)
		(fp_line
			(start 0.4953 -0.2032)
			(end -0.4953 -0.2032)
			(stroke
				(width 0.1)
				(type default)
			)
			(layer "B.Fab")
		)
		(fp_line
			(start 0.4953 1.6002)
			(end 0.4953 -0.2032)
			(stroke
				(width 0.1)
				(type default)
			)
			(layer "B.Fab")
		)
		(pad "1" smd rect
			(at 0 0 180)
			(size 0.762 0.889)
			(layers "B.Cu" "B.Mask" "B.Paste")
			(net "PVDDQ_DEF")
		)
		(pad "2" smd rect
			(at 0 1.397 180)
			(size 0.762 0.889)
			(layers "B.Cu" "B.Mask" "B.Paste")
			(net "GND")
		)
		(zone
			(layer "B.Cu")
			(hatch none 0.5)
			(connect_pads
				(clearance 0)
			)
			(min_thickness 0.25)
			(keepout
				(tracks not_allowed)
				(vias allowed)
				(pads allowed)
				(copperpour not_allowed)
				(footprints allowed)
			)
			(placement
				(enabled no)
				(sheetname "")
			)
			(fill
				(thermal_gap 0.5)
				(thermal_bridge_width 0.5)
				(island_removal_mode 0)
			)
			(polygon
				(pts
					(xy 181.254654 -150.371048) (xy 180.492654 -150.371048) (xy 180.492654 -149.863048) (xy 181.254654 -149.863048)
				)
			)
		)
	)
)
